(kicad_pcb
	(version 20260206)
	(generator "pcbnew")
	(generator_version "10.0")
	(general
		(thickness 1.6)
		(legacy_teardrops no)
	)
	(paper "A4")
	(title_block
		(title "04192023_DAF0TMB3IC0_F0TG_MB_C_brd_V02_OCP.brd")
		(comment 1 "Grand Teton / footprint 1808 of 8354 (J16), pads 114-226 of 291")
	)
	(layers
		(0 "F.Cu" signal "TOP")
		(4 "In1.Cu" signal "GND")
		(6 "In2.Cu" signal "IN1")
		(8 "In3.Cu" signal "GND1")
		(10 "In4.Cu" signal "IN2")
		(12 "In5.Cu" signal "GND2")
		(14 "In6.Cu" signal "IN3")
		(16 "In7.Cu" signal "GND3")
		(18 "In8.Cu" signal "VCC")
		(20 "In9.Cu" signal "VCC1")
		(22 "In10.Cu" signal "GND4")
		(24 "In11.Cu" signal "IN4")
		(26 "In12.Cu" signal "GND5")
		(28 "In13.Cu" signal "IN5")
		(30 "In14.Cu" signal "GND6")
		(32 "In15.Cu" signal "IN6")
		(34 "In16.Cu" signal "GND7")
		(2 "B.Cu" signal "BOTTOM")
		(9 "F.Adhes" user "F.Adhesive")
		(11 "B.Adhes" user "B.Adhesive")
		(13 "F.Paste" user "Package Geometry/Pastemask Top")
		(15 "B.Paste" user "Package Geometry/Pastemask Bottom")
		(5 "F.SilkS" user "Ref Des/Silkscreen Top")
		(7 "B.SilkS" user "Ref Des/Silkscreen Bottom")
		(1 "F.Mask" user "Board Geometry/Soldermask Top")
		(3 "B.Mask" user "Board Geometry/Soldermask Bottom")
		(17 "Dwgs.User" user "User.Drawings")
		(19 "Cmts.User" user "User.Comments")
		(21 "Eco1.User" user "User.Eco1")
		(23 "Eco2.User" user "User.Eco2")
		(25 "Edge.Cuts" user "Board Geometry/Outline")
		(27 "Margin" user)
		(31 "F.CrtYd" user "Package Geometry/Place Bound Top")
		(29 "B.CrtYd" user "Package Geometry/Place Bound Bottom")
		(35 "F.Fab" user "Ref Des/Assembly Top")
		(33 "B.Fab" user "Ref Des/Assembly Bottom")
	)
	(footprint ""
		(layer "F.Cu")
		(at 414.418018 -255.560068 180)
		(property "Reference" "J16"
			(at 1.474216 81.889092 0)
			(unlocked yes)
			(layer "F.SilkS")
			(effects
				(font
					(size 0.7874 0.5842)
					(thickness 0.1524)
				)
			)
		)
		(property "Value" ""
			(at 0 0 180)
			(layer "F.Fab")
			(effects
				(font
					(size 1.27 1.27)
				)
			)
		)
		(duplicate_pad_numbers_are_jumpers no)
		(pad "114" smd rect
			(at -2.050034 37.824918 90)
			(size 0.519938 1.4986)
			(layers "F.Cu" "F.Mask" "F.Paste")
			(net "GND")
		)
		(pad "115" smd rect
			(at -2.050034 38.675056 90)
			(size 0.519938 1.4986)
			(layers "F.Cu" "F.Mask" "F.Paste")
			(net "M_G_CPU0_SB_DQS_DP<1>")
		)
		(pad "116" smd rect
			(at -2.050034 39.52494 90)
			(size 0.519938 1.4986)
			(layers "F.Cu" "F.Mask" "F.Paste")
			(net "M_G_CPU0_SB_DQS_DN<1>")
		)
		(pad "117" smd rect
			(at -2.050034 40.375078 90)
			(size 0.519938 1.4986)
			(layers "F.Cu" "F.Mask" "F.Paste")
			(net "GND")
		)
		(pad "118" smd rect
			(at -2.050034 41.224962 90)
			(size 0.519938 1.4986)
			(layers "F.Cu" "F.Mask" "F.Paste")
			(net "M_G_CPU0_SB_DQ<12>")
		)
		(pad "119" smd rect
			(at -2.050034 42.0751 90)
			(size 0.519938 1.4986)
			(layers "F.Cu" "F.Mask" "F.Paste")
			(net "GND")
		)
		(pad "120" smd rect
			(at -2.050034 42.924984 90)
			(size 0.519938 1.4986)
			(layers "F.Cu" "F.Mask" "F.Paste")
			(net "M_G_CPU0_SB_DQ<13>")
		)
		(pad "121" smd rect
			(at -2.050034 43.775122 90)
			(size 0.519938 1.4986)
			(layers "F.Cu" "F.Mask" "F.Paste")
			(net "GND")
		)
		(pad "122" smd rect
			(at -2.050034 44.625006 90)
			(size 0.519938 1.4986)
			(layers "F.Cu" "F.Mask" "F.Paste")
			(net "M_G_CPU0_SB_DQ<16>")
		)
		(pad "123" smd rect
			(at -2.050034 45.47489 90)
			(size 0.519938 1.4986)
			(layers "F.Cu" "F.Mask" "F.Paste")
			(net "GND")
		)
		(pad "124" smd rect
			(at -2.050034 46.325028 90)
			(size 0.519938 1.4986)
			(layers "F.Cu" "F.Mask" "F.Paste")
			(net "M_G_CPU0_SB_DQ<17>")
		)
		(pad "125" smd rect
			(at -2.050034 47.174912 90)
			(size 0.519938 1.4986)
			(layers "F.Cu" "F.Mask" "F.Paste")
			(net "GND")
		)
		(pad "126" smd rect
			(at -2.050034 48.02505 90)
			(size 0.519938 1.4986)
			(layers "F.Cu" "F.Mask" "F.Paste")
			(net "M_G_CPU0_SB_DQS_DP<2>")
		)
		(pad "127" smd rect
			(at -2.050034 48.874934 90)
			(size 0.519938 1.4986)
			(layers "F.Cu" "F.Mask" "F.Paste")
			(net "M_G_CPU0_SB_DQS_DN<2>")
		)
		(pad "128" smd rect
			(at -2.050034 49.725072 90)
			(size 0.519938 1.4986)
			(layers "F.Cu" "F.Mask" "F.Paste")
			(net "GND")
		)
		(pad "129" smd rect
			(at -2.050034 50.574956 90)
			(size 0.519938 1.4986)
			(layers "F.Cu" "F.Mask" "F.Paste")
			(net "M_G_CPU0_SB_DQ<20>")
		)
		(pad "130" smd rect
			(at -2.050034 51.425094 90)
			(size 0.519938 1.4986)
			(layers "F.Cu" "F.Mask" "F.Paste")
			(net "GND")
		)
		(pad "131" smd rect
			(at -2.050034 52.274978 90)
			(size 0.519938 1.4986)
			(layers "F.Cu" "F.Mask" "F.Paste")
			(net "M_G_CPU0_SB_DQ<21>")
		)
		(pad "132" smd rect
			(at -2.050034 53.125116 90)
			(size 0.519938 1.4986)
			(layers "F.Cu" "F.Mask" "F.Paste")
			(net "GND")
		)
		(pad "133" smd rect
			(at -2.050034 53.975 90)
			(size 0.519938 1.4986)
			(layers "F.Cu" "F.Mask" "F.Paste")
			(net "M_G_CPU0_SB_DQ<24>")
		)
		(pad "134" smd rect
			(at -2.050034 54.824884 90)
			(size 0.519938 1.4986)
			(layers "F.Cu" "F.Mask" "F.Paste")
			(net "GND")
		)
		(pad "135" smd rect
			(at -2.050034 55.675022 90)
			(size 0.519938 1.4986)
			(layers "F.Cu" "F.Mask" "F.Paste")
			(net "M_G_CPU0_SB_DQ<25>")
		)
		(pad "136" smd rect
			(at -2.050034 56.524906 90)
			(size 0.519938 1.4986)
			(layers "F.Cu" "F.Mask" "F.Paste")
			(net "GND")
		)
		(pad "137" smd rect
			(at -2.050034 57.375044 90)
			(size 0.519938 1.4986)
			(layers "F.Cu" "F.Mask" "F.Paste")
			(net "M_G_CPU0_SB_DQS_DP<3>")
		)
		(pad "138" smd rect
			(at -2.050034 58.224928 90)
			(size 0.519938 1.4986)
			(layers "F.Cu" "F.Mask" "F.Paste")
			(net "M_G_CPU0_SB_DQS_DN<3>")
		)
		(pad "139" smd rect
			(at -2.050034 59.075066 90)
			(size 0.519938 1.4986)
			(layers "F.Cu" "F.Mask" "F.Paste")
			(net "GND")
		)
		(pad "140" smd rect
			(at -2.050034 59.92495 90)
			(size 0.519938 1.4986)
			(layers "F.Cu" "F.Mask" "F.Paste")
			(net "M_G_CPU0_SB_DQ<28>")
		)
		(pad "141" smd rect
			(at -2.050034 60.775088 90)
			(size 0.519938 1.4986)
			(layers "F.Cu" "F.Mask" "F.Paste")
			(net "GND")
		)
		(pad "142" smd rect
			(at -2.050034 61.624972 90)
			(size 0.519938 1.4986)
			(layers "F.Cu" "F.Mask" "F.Paste")
			(net "M_G_CPU0_SB_DQ<29>")
		)
		(pad "143" smd rect
			(at -2.050034 62.47511 90)
			(size 0.519938 1.4986)
			(layers "F.Cu" "F.Mask" "F.Paste")
			(net "GND")
		)
		(pad "144" smd rect
			(at -2.050034 63.324994 90)
			(size 0.519938 1.4986)
			(layers "F.Cu" "F.Mask" "F.Paste")
			(net "Net_2334")
		)
		(pad "145" smd rect
			(at 2.050034 -63.324994 90)
			(size 0.519938 1.4986)
			(layers "F.Cu" "F.Mask" "F.Paste")
			(net "P12V_MEM_CPU0")
		)
		(pad "146" smd rect
			(at 2.050034 -62.47511 90)
			(size 0.519938 1.4986)
			(layers "F.Cu" "F.Mask" "F.Paste")
			(net "P12V_MEM_CPU0")
		)
		(pad "147" smd rect
			(at 2.050034 -61.624972 90)
			(size 0.519938 1.4986)
			(layers "F.Cu" "F.Mask" "F.Paste")
			(net "PWRGD_CHG_CPU0_DIMM0")
		)
		(pad "148" smd rect
			(at 2.050034 -60.775088 90)
			(size 0.519938 1.4986)
			(layers "F.Cu" "F.Mask" "F.Paste")
			(net "PD_CHG_CPU0_DIMM0_SAA")
		)
		(pad "149" smd rect
			(at 2.050034 -59.92495 90)
			(size 0.519938 1.4986)
			(layers "F.Cu" "F.Mask" "F.Paste")
			(net "Net_2335")
		)
		(pad "150" smd rect
			(at 2.050034 -59.075066 90)
			(size 0.519938 1.4986)
			(layers "F.Cu" "F.Mask" "F.Paste")
			(net "Net_2336")
		)
		(pad "151" smd rect
			(at 2.050034 -58.224928 90)
			(size 0.519938 1.4986)
			(layers "F.Cu" "F.Mask" "F.Paste")
			(net "GND")
		)
		(pad "152" smd rect
			(at 2.050034 -57.375044 90)
			(size 0.519938 1.4986)
			(layers "F.Cu" "F.Mask" "F.Paste")
			(net "M_G_CPU0_SA_DQ<2>")
		)
		(pad "153" smd rect
			(at 2.050034 -56.524906 90)
			(size 0.519938 1.4986)
			(layers "F.Cu" "F.Mask" "F.Paste")
			(net "GND")
		)
		(pad "154" smd rect
			(at 2.050034 -55.675022 90)
			(size 0.519938 1.4986)
			(layers "F.Cu" "F.Mask" "F.Paste")
			(net "M_G_CPU0_SA_DQ<3>")
		)
		(pad "155" smd rect
			(at 2.050034 -54.824884 90)
			(size 0.519938 1.4986)
			(layers "F.Cu" "F.Mask" "F.Paste")
			(net "GND")
		)
		(pad "156" smd rect
			(at 2.050034 -53.975 90)
			(size 0.519938 1.4986)
			(layers "F.Cu" "F.Mask" "F.Paste")
			(net "M_G_CPU0_SA_DQS_DN<5>")
		)
		(pad "157" smd rect
			(at 2.050034 -53.125116 90)
			(size 0.519938 1.4986)
			(layers "F.Cu" "F.Mask" "F.Paste")
			(net "M_G_CPU0_SA_DQS_DP<5>")
		)
		(pad "158" smd rect
			(at 2.050034 -52.274978 90)
			(size 0.519938 1.4986)
			(layers "F.Cu" "F.Mask" "F.Paste")
			(net "GND")
		)
		(pad "159" smd rect
			(at 2.050034 -51.425094 90)
			(size 0.519938 1.4986)
			(layers "F.Cu" "F.Mask" "F.Paste")
			(net "M_G_CPU0_SA_DQ<6>")
		)
		(pad "160" smd rect
			(at 2.050034 -50.574956 90)
			(size 0.519938 1.4986)
			(layers "F.Cu" "F.Mask" "F.Paste")
			(net "GND")
		)
		(pad "161" smd rect
			(at 2.050034 -49.725072 90)
			(size 0.519938 1.4986)
			(layers "F.Cu" "F.Mask" "F.Paste")
			(net "M_G_CPU0_SA_DQ<7>")
		)
		(pad "162" smd rect
			(at 2.050034 -48.874934 90)
			(size 0.519938 1.4986)
			(layers "F.Cu" "F.Mask" "F.Paste")
			(net "GND")
		)
		(pad "163" smd rect
			(at 2.050034 -48.02505 90)
			(size 0.519938 1.4986)
			(layers "F.Cu" "F.Mask" "F.Paste")
			(net "M_G_CPU0_SA_DQ<10>")
		)
		(pad "164" smd rect
			(at 2.050034 -47.174912 90)
			(size 0.519938 1.4986)
			(layers "F.Cu" "F.Mask" "F.Paste")
			(net "GND")
		)
		(pad "165" smd rect
			(at 2.050034 -46.325028 90)
			(size 0.519938 1.4986)
			(layers "F.Cu" "F.Mask" "F.Paste")
			(net "M_G_CPU0_SA_DQ<11>")
		)
		(pad "166" smd rect
			(at 2.050034 -45.47489 90)
			(size 0.519938 1.4986)
			(layers "F.Cu" "F.Mask" "F.Paste")
			(net "GND")
		)
		(pad "167" smd rect
			(at 2.050034 -44.625006 90)
			(size 0.519938 1.4986)
			(layers "F.Cu" "F.Mask" "F.Paste")
			(net "M_G_CPU0_SA_DQS_DN<6>")
		)
		(pad "168" smd rect
			(at 2.050034 -43.775122 90)
			(size 0.519938 1.4986)
			(layers "F.Cu" "F.Mask" "F.Paste")
			(net "M_G_CPU0_SA_DQS_DP<6>")
		)
		(pad "169" smd rect
			(at 2.050034 -42.924984 90)
			(size 0.519938 1.4986)
			(layers "F.Cu" "F.Mask" "F.Paste")
			(net "GND")
		)
		(pad "170" smd rect
			(at 2.050034 -42.0751 90)
			(size 0.519938 1.4986)
			(layers "F.Cu" "F.Mask" "F.Paste")
			(net "M_G_CPU0_SA_DQ<14>")
		)
		(pad "171" smd rect
			(at 2.050034 -41.224962 90)
			(size 0.519938 1.4986)
			(layers "F.Cu" "F.Mask" "F.Paste")
			(net "GND")
		)
		(pad "172" smd rect
			(at 2.050034 -40.375078 90)
			(size 0.519938 1.4986)
			(layers "F.Cu" "F.Mask" "F.Paste")
			(net "M_G_CPU0_SA_DQ<15>")
		)
		(pad "173" smd rect
			(at 2.050034 -39.52494 90)
			(size 0.519938 1.4986)
			(layers "F.Cu" "F.Mask" "F.Paste")
			(net "GND")
		)
		(pad "174" smd rect
			(at 2.050034 -38.675056 90)
			(size 0.519938 1.4986)
			(layers "F.Cu" "F.Mask" "F.Paste")
			(net "M_G_CPU0_SA_DQ<18>")
		)
		(pad "175" smd rect
			(at 2.050034 -37.824918 90)
			(size 0.519938 1.4986)
			(layers "F.Cu" "F.Mask" "F.Paste")
			(net "GND")
		)
		(pad "176" smd rect
			(at 2.050034 -36.975034 90)
			(size 0.519938 1.4986)
			(layers "F.Cu" "F.Mask" "F.Paste")
			(net "M_G_CPU0_SA_DQ<19>")
		)
		(pad "177" smd rect
			(at 2.050034 -36.124896 90)
			(size 0.519938 1.4986)
			(layers "F.Cu" "F.Mask" "F.Paste")
			(net "GND")
		)
		(pad "178" smd rect
			(at 2.050034 -35.275012 90)
			(size 0.519938 1.4986)
			(layers "F.Cu" "F.Mask" "F.Paste")
			(net "M_G_CPU0_SA_DQS_DN<7>")
		)
		(pad "179" smd rect
			(at 2.050034 -34.425128 90)
			(size 0.519938 1.4986)
			(layers "F.Cu" "F.Mask" "F.Paste")
			(net "M_G_CPU0_SA_DQS_DP<7>")
		)
		(pad "180" smd rect
			(at 2.050034 -33.57499 90)
			(size 0.519938 1.4986)
			(layers "F.Cu" "F.Mask" "F.Paste")
			(net "GND")
		)
		(pad "181" smd rect
			(at 2.050034 -32.725106 90)
			(size 0.519938 1.4986)
			(layers "F.Cu" "F.Mask" "F.Paste")
			(net "M_G_CPU0_SA_DQ<22>")
		)
		(pad "182" smd rect
			(at 2.050034 -31.874968 90)
			(size 0.519938 1.4986)
			(layers "F.Cu" "F.Mask" "F.Paste")
			(net "GND")
		)
		(pad "183" smd rect
			(at 2.050034 -31.025084 90)
			(size 0.519938 1.4986)
			(layers "F.Cu" "F.Mask" "F.Paste")
			(net "M_G_CPU0_SA_DQ<23>")
		)
		(pad "184" smd rect
			(at 2.050034 -30.174946 90)
			(size 0.519938 1.4986)
			(layers "F.Cu" "F.Mask" "F.Paste")
			(net "GND")
		)
		(pad "185" smd rect
			(at 2.050034 -29.325062 90)
			(size 0.519938 1.4986)
			(layers "F.Cu" "F.Mask" "F.Paste")
			(net "M_G_CPU0_SA_DQ<26>")
		)
		(pad "186" smd rect
			(at 2.050034 -28.474924 90)
			(size 0.519938 1.4986)
			(layers "F.Cu" "F.Mask" "F.Paste")
			(net "GND")
		)
		(pad "187" smd rect
			(at 2.050034 -27.62504 90)
			(size 0.519938 1.4986)
			(layers "F.Cu" "F.Mask" "F.Paste")
			(net "M_G_CPU0_SA_DQ<27>")
		)
		(pad "188" smd rect
			(at 2.050034 -26.774902 90)
			(size 0.519938 1.4986)
			(layers "F.Cu" "F.Mask" "F.Paste")
			(net "GND")
		)
		(pad "189" smd rect
			(at 2.050034 -25.925018 90)
			(size 0.519938 1.4986)
			(layers "F.Cu" "F.Mask" "F.Paste")
			(net "M_G_CPU0_SA_DQS_DN<8>")
		)
		(pad "190" smd rect
			(at 2.050034 -25.07488 90)
			(size 0.519938 1.4986)
			(layers "F.Cu" "F.Mask" "F.Paste")
			(net "M_G_CPU0_SA_DQS_DP<8>")
		)
		(pad "191" smd rect
			(at 2.050034 -24.224996 90)
			(size 0.519938 1.4986)
			(layers "F.Cu" "F.Mask" "F.Paste")
			(net "GND")
		)
		(pad "192" smd rect
			(at 2.050034 -23.375112 90)
			(size 0.519938 1.4986)
			(layers "F.Cu" "F.Mask" "F.Paste")
			(net "M_G_CPU0_SA_DQ<30>")
		)
		(pad "193" smd rect
			(at 2.050034 -22.524974 90)
			(size 0.519938 1.4986)
			(layers "F.Cu" "F.Mask" "F.Paste")
			(net "GND")
		)
		(pad "194" smd rect
			(at 2.050034 -21.67509 90)
			(size 0.519938 1.4986)
			(layers "F.Cu" "F.Mask" "F.Paste")
			(net "M_G_CPU0_SA_DQ<31>")
		)
		(pad "195" smd rect
			(at 2.050034 -20.824952 90)
			(size 0.519938 1.4986)
			(layers "F.Cu" "F.Mask" "F.Paste")
			(net "GND")
		)
		(pad "196" smd rect
			(at 2.050034 -19.975068 90)
			(size 0.519938 1.4986)
			(layers "F.Cu" "F.Mask" "F.Paste")
			(net "M_G_CPU0_SA_CB<2>")
		)
		(pad "197" smd rect
			(at 2.050034 -19.12493 90)
			(size 0.519938 1.4986)
			(layers "F.Cu" "F.Mask" "F.Paste")
			(net "GND")
		)
		(pad "198" smd rect
			(at 2.050034 -18.275046 90)
			(size 0.519938 1.4986)
			(layers "F.Cu" "F.Mask" "F.Paste")
			(net "M_G_CPU0_SA_CB<3>")
		)
		(pad "199" smd rect
			(at 2.050034 -17.424908 90)
			(size 0.519938 1.4986)
			(layers "F.Cu" "F.Mask" "F.Paste")
			(net "GND")
		)
		(pad "200" smd rect
			(at 2.050034 -16.575024 90)
			(size 0.519938 1.4986)
			(layers "F.Cu" "F.Mask" "F.Paste")
			(net "M_G_CPU0_SA_DQS_DN<9>")
		)
		(pad "201" smd rect
			(at 2.050034 -15.724886 90)
			(size 0.519938 1.4986)
			(layers "F.Cu" "F.Mask" "F.Paste")
			(net "M_G_CPU0_SA_DQS_DP<9>")
		)
		(pad "202" smd rect
			(at 2.050034 -14.875002 90)
			(size 0.519938 1.4986)
			(layers "F.Cu" "F.Mask" "F.Paste")
			(net "GND")
		)
		(pad "203" smd rect
			(at 2.050034 -14.025118 90)
			(size 0.519938 1.4986)
			(layers "F.Cu" "F.Mask" "F.Paste")
			(net "M_G_CPU0_SA_CB<6>")
		)
		(pad "204" smd rect
			(at 2.050034 -13.17498 90)
			(size 0.519938 1.4986)
			(layers "F.Cu" "F.Mask" "F.Paste")
			(net "GND")
		)
		(pad "205" smd rect
			(at 2.050034 -12.325096 90)
			(size 0.519938 1.4986)
			(layers "F.Cu" "F.Mask" "F.Paste")
			(net "M_G_CPU0_SA_CB<7>")
		)
		(pad "206" smd rect
			(at 2.050034 -11.474958 90)
			(size 0.519938 1.4986)
			(layers "F.Cu" "F.Mask" "F.Paste")
			(net "GND")
		)
		(pad "207" smd rect
			(at 2.050034 -10.625074 90)
			(size 0.519938 1.4986)
			(layers "F.Cu" "F.Mask" "F.Paste")
			(net "M_G_CPU0_RESET_N")
		)
		(pad "208" smd rect
			(at 2.050034 -9.774936 90)
			(size 0.519938 1.4986)
			(layers "F.Cu" "F.Mask" "F.Paste")
			(net "GND")
		)
		(pad "209" smd rect
			(at 2.050034 -8.925052 90)
			(size 0.519938 1.4986)
			(layers "F.Cu" "F.Mask" "F.Paste")
			(net "M_G_CPU0_SA_CS_N<1>")
		)
		(pad "210" smd rect
			(at 2.050034 -8.074914 90)
			(size 0.519938 1.4986)
			(layers "F.Cu" "F.Mask" "F.Paste")
			(net "GND")
		)
		(pad "211" smd rect
			(at 2.050034 -7.22503 90)
			(size 0.519938 1.4986)
			(layers "F.Cu" "F.Mask" "F.Paste")
			(net "M_G_CPU0_SA_CA<1>")
		)
		(pad "212" smd rect
			(at 2.050034 -6.374892 90)
			(size 0.519938 1.4986)
			(layers "F.Cu" "F.Mask" "F.Paste")
			(net "GND")
		)
		(pad "213" smd rect
			(at 2.050034 -5.525008 90)
			(size 0.519938 1.4986)
			(layers "F.Cu" "F.Mask" "F.Paste")
			(net "M_G_CPU0_SA_CA<3>")
		)
		(pad "214" smd rect
			(at 2.050034 -4.675124 90)
			(size 0.519938 1.4986)
			(layers "F.Cu" "F.Mask" "F.Paste")
			(net "GND")
		)
		(pad "215" smd rect
			(at 2.050034 -3.824986 90)
			(size 0.519938 1.4986)
			(layers "F.Cu" "F.Mask" "F.Paste")
			(net "M_G_CPU0_SA_CA<5>")
		)
		(pad "216" smd rect
			(at 2.050034 -2.975102 90)
			(size 0.519938 1.4986)
			(layers "F.Cu" "F.Mask" "F.Paste")
			(net "GND")
		)
		(pad "217" smd rect
			(at 2.050034 -2.124964 90)
			(size 0.519938 1.4986)
			(layers "F.Cu" "F.Mask" "F.Paste")
			(net "M_G_CPU0_CLK_DP<0>")
		)
		(pad "218" smd rect
			(at 2.050034 -1.27508 90)
			(size 0.519938 1.4986)
			(layers "F.Cu" "F.Mask" "F.Paste")
			(net "M_G_CPU0_CLK_DN<0>")
		)
		(pad "219" smd rect
			(at 2.050034 -0.424942 90)
			(size 0.519938 1.4986)
			(layers "F.Cu" "F.Mask" "F.Paste")
			(net "GND")
		)
		(pad "220" smd rect
			(at 2.050034 5.525008 90)
			(size 0.519938 1.4986)
			(layers "F.Cu" "F.Mask" "F.Paste")
			(net "Net_2337")
		)
		(pad "221" smd rect
			(at 2.050034 6.374892 90)
			(size 0.519938 1.4986)
			(layers "F.Cu" "F.Mask" "F.Paste")
			(net "M_G_CPU0_SB_CA<1>")
		)
		(pad "222" smd rect
			(at 2.050034 7.22503 90)
			(size 0.519938 1.4986)
			(layers "F.Cu" "F.Mask" "F.Paste")
			(net "GND")
		)
		(pad "223" smd rect
			(at 2.050034 8.074914 90)
			(size 0.519938 1.4986)
			(layers "F.Cu" "F.Mask" "F.Paste")
			(net "M_G_CPU0_SB_CA<3>")
		)
		(pad "224" smd rect
			(at 2.050034 8.925052 90)
			(size 0.519938 1.4986)
			(layers "F.Cu" "F.Mask" "F.Paste")
			(net "GND")
		)
		(pad "225" smd rect
			(at 2.050034 9.774936 90)
			(size 0.519938 1.4986)
			(layers "F.Cu" "F.Mask" "F.Paste")
			(net "M_G_CPU0_SB_CA<5>")
		)
		(pad "226" smd rect
			(at 2.050034 10.625074 90)
			(size 0.519938 1.4986)
			(layers "F.Cu" "F.Mask" "F.Paste")
			(net "GND")
		)
	)
)
